(kicad_pcb
	(version 20260206)
	(generator "pcbnew")
	(generator_version "10.0")
	(general
		(thickness 1.6)
		(legacy_teardrops no)
	)
	(paper "A4")
	(title_block
		(title "Wiwynn_Tioga_Pass_MB.brd")
		(comment 1 "Tioga Pass / footprints 2071-2077 of 4770")
	)
	(layers
		(0 "F.Cu" signal "TOP")
		(4 "In1.Cu" signal "L2GND")
		(6 "In2.Cu" signal "L3")
		(8 "In3.Cu" signal "L4GND")
		(10 "In4.Cu" signal "L5")
		(12 "In5.Cu" signal "L6GND")
		(14 "In6.Cu" signal "L7VCC")
		(16 "In7.Cu" signal "L8VCC")
		(18 "In8.Cu" signal "L9GND")
		(20 "In9.Cu" signal "L10")
		(22 "In10.Cu" signal "L11GND")
		(24 "In11.Cu" signal "L12")
		(26 "In12.Cu" signal "L13GND")
		(2 "B.Cu" signal "BOTTOM")
		(9 "F.Adhes" user "F.Adhesive")
		(11 "B.Adhes" user "B.Adhesive")
		(13 "F.Paste" user "Package Geometry/Pastemask Top")
		(15 "B.Paste" user "Package Geometry/Pastemask Bottom")
		(5 "F.SilkS" user "Ref Des/Silkscreen Top")
		(7 "B.SilkS" user "Ref Des/Silkscreen Bottom")
		(1 "F.Mask" user "Board Geometry/Soldermask Top")
		(3 "B.Mask" user "Board Geometry/Soldermask Bottom")
		(17 "Dwgs.User" user "User.Drawings")
		(19 "Cmts.User" user "User.Comments")
		(21 "Eco1.User" user "User.Eco1")
		(23 "Eco2.User" user "User.Eco2")
		(25 "Edge.Cuts" user "Board Geometry/Outline")
		(27 "Margin" user)
		(31 "F.CrtYd" user "Package Geometry/Place Bound Top")
		(29 "B.CrtYd" user "Package Geometry/Place Bound Bottom")
		(35 "F.Fab" user "Ref Des/Assembly Top")
		(33 "B.Fab" user "Ref Des/Assembly Bottom")
	)
	(footprint ""
		(layer "F.Cu")
		(at 35.7886 -61.214 -90)
		(property "Reference" "RT18"
			(at 0 0 270)
			(layer "F.SilkS")
			(hide yes)
			(effects
				(font
					(size 1.27 1.27)
				)
			)
		)
		(property "Value" "*"
			(at -0.0254 -2.6289 270)
			(unlocked yes)
			(layer "F.Fab")
			(hide yes)
			(effects
				(font
					(size 1.27 1.016)
					(thickness 0.1524)
				)
			)
		)
		(property "Device Type" "1R3F-GP_RCL_GP-1R3F-GP,64.1R00A"
			(at -0.0254 -4.1529 270)
			(unlocked yes)
			(layer "F.Fab")
			(hide yes)
			(effects
				(font
					(size 1.27 1.016)
					(thickness 0.1524)
				)
			)
		)
		(duplicate_pad_numbers_are_jumpers no)
		(fp_line
			(start -0.4826 0)
			(end -0.2032 0)
			(stroke
				(width 0.2032)
				(type default)
			)
			(layer "F.SilkS")
		)
		(fp_line
			(start 0.2032 0)
			(end 0.4826 0)
			(stroke
				(width 0.2032)
				(type default)
			)
			(layer "F.SilkS")
		)
		(fp_rect
			(start -0.5842 1.3335)
			(end 0.5842 -1.3335)
			(stroke
				(width 0)
				(type default)
			)
			(fill no)
			(layer "F.CrtYd")
		)
		(fp_rect
			(start -0.5842 1.3335)
			(end 0.5842 -1.3335)
			(stroke
				(width 0)
				(type default)
			)
			(fill no)
			(layer "F.Fab")
		)
		(pad "1" smd custom
			(at 0 -0.762 270)
			(size 0.2159 0.2159)
			(layers "F.Cu" "F.Mask" "F.Paste")
			(net "VR_PVCCIN_CPU1_PHASE2_RC")
			(options
				(clearance outline)
				(anchor circle)
			)
			(primitives
				(gr_poly
					(pts
						(arc
							(start -0.3302 -0.4318)
							(mid -0.402042 -0.402042)
							(end -0.4318 -0.3302)
						)
						(arc
							(start -0.4318 0.3302)
							(mid -0.402042 0.402042)
							(end -0.3302 0.4318)
						)
						(arc
							(start 0.3302 0.4318)
							(mid 0.402042 0.402042)
							(end 0.4318 0.3302)
						)
						(arc
							(start 0.4318 -0.3302)
							(mid 0.402042 -0.402042)
							(end 0.3302 -0.4318)
						)
					)
					(width 0)
					(fill yes)
				)
			)
		)
		(pad "2" smd custom
			(at 0 0.762 270)
			(size 0.2159 0.2159)
			(layers "F.Cu" "F.Mask" "F.Paste")
			(net "GND")
			(options
				(clearance outline)
				(anchor circle)
			)
			(primitives
				(gr_poly
					(pts
						(arc
							(start -0.3302 -0.4318)
							(mid -0.402042 -0.402042)
							(end -0.4318 -0.3302)
						)
						(arc
							(start -0.4318 0.3302)
							(mid -0.402042 0.402042)
							(end -0.3302 0.4318)
						)
						(arc
							(start 0.3302 0.4318)
							(mid 0.402042 0.402042)
							(end 0.4318 0.3302)
						)
						(arc
							(start 0.4318 -0.3302)
							(mid 0.402042 -0.402042)
							(end 0.3302 -0.4318)
						)
					)
					(width 0)
					(fill yes)
				)
			)
		)
	)
	(footprint ""
		(layer "F.Cu")
		(at 266.0142 -84.7598)
		(property "Reference" "C5D7"
			(at 0 0 0)
			(layer "F.SilkS")
			(hide yes)
			(effects
				(font
					(size 1.27 1.27)
				)
			)
		)
		(property "Value" ""
			(at 0 0 0)
			(layer "F.Fab")
			(effects
				(font
					(size 1.27 1.27)
				)
			)
		)
		(duplicate_pad_numbers_are_jumpers no)
		(fp_poly
			(pts
				(xy -0.4953 -0.2032) (xy 0.4953 -0.2032) (xy 0.4953 1.6002) (xy -0.4953 1.6002)
			)
			(stroke
				(width 0)
				(type default)
			)
			(fill no)
			(layer "F.CrtYd")
		)
		(fp_line
			(start -0.4953 -0.2032)
			(end 0.4953 -0.2032)
			(stroke
				(width 0.1)
				(type default)
			)
			(layer "F.Fab")
		)
		(fp_line
			(start -0.4953 1.6002)
			(end -0.4953 -0.2032)
			(stroke
				(width 0.1)
				(type default)
			)
			(layer "F.Fab")
		)
		(fp_line
			(start 0.4953 -0.2032)
			(end 0.4953 1.6002)
			(stroke
				(width 0.1)
				(type default)
			)
			(layer "F.Fab")
		)
		(fp_line
			(start 0.4953 1.6002)
			(end -0.4953 1.6002)
			(stroke
				(width 0.1)
				(type default)
			)
			(layer "F.Fab")
		)
		(pad "1" smd rect
			(at 0 0)
			(size 0.762 0.889)
			(layers "F.Cu" "F.Mask" "F.Paste")
			(net "PVDDQ_DEF")
		)
		(pad "2" smd rect
			(at 0 1.397)
			(size 0.762 0.889)
			(layers "F.Cu" "F.Mask" "F.Paste")
			(net "GND")
		)
		(zone
			(layer "F.Cu")
			(hatch none 0.5)
			(connect_pads
				(clearance 0)
			)
			(min_thickness 0.25)
			(keepout
				(tracks not_allowed)
				(vias allowed)
				(pads allowed)
				(copperpour not_allowed)
				(footprints allowed)
			)
			(placement
				(enabled no)
				(sheetname "")
			)
			(fill
				(thermal_gap 0.5)
				(thermal_bridge_width 0.5)
				(island_removal_mode 0)
			)
			(polygon
				(pts
					(xy 265.6332 -84.3153) (xy 266.3952 -84.3153) (xy 266.3952 -83.8073) (xy 265.6332 -83.8073)
				)
			)
		)
	)
	(footprint ""
		(layer "F.Cu")
		(at 343.9668 -32.8803 90)
		(property "Reference" "R7F7"
			(at 0 0 90)
			(layer "F.SilkS")
			(hide yes)
			(effects
				(font
					(size 1.27 1.27)
				)
			)
		)
		(property "Value" ""
			(at 0 0 90)
			(layer "F.Fab")
			(effects
				(font
					(size 1.27 1.27)
				)
			)
		)
		(duplicate_pad_numbers_are_jumpers no)
		(fp_rect
			(start -0.2794 -0.1016)
			(end 0.2794 0.9906)
			(stroke
				(width 0)
				(type default)
			)
			(fill no)
			(layer "F.CrtYd")
		)
		(fp_line
			(start 0.2794 -0.1016)
			(end -0.2794 -0.1016)
			(stroke
				(width 0.1)
				(type default)
			)
			(layer "F.Fab")
		)
		(fp_line
			(start -0.2794 -0.1016)
			(end -0.2794 0.9906)
			(stroke
				(width 0.1)
				(type default)
			)
			(layer "F.Fab")
		)
		(fp_line
			(start 0.2794 0.9906)
			(end 0.2794 -0.1016)
			(stroke
				(width 0.1)
				(type default)
			)
			(layer "F.Fab")
		)
		(fp_line
			(start -0.2794 0.9906)
			(end 0.2794 0.9906)
			(stroke
				(width 0.1)
				(type default)
			)
			(layer "F.Fab")
		)
		(pad "1" smd rect
			(at 0 0 90)
			(size 0.508 0.508)
			(layers "F.Cu" "F.Mask" "F.Paste")
			(net "VR_PVPP_ABC_SNUB")
		)
		(pad "2" smd rect
			(at 0 0.889 90)
			(size 0.508 0.508)
			(layers "F.Cu" "F.Mask" "F.Paste")
			(net "GND")
		)
		(zone
			(layer "F.Cu")
			(hatch none 0.5)
			(connect_pads
				(clearance 0)
			)
			(min_thickness 0.25)
			(keepout
				(tracks not_allowed)
				(vias allowed)
				(pads allowed)
				(copperpour not_allowed)
				(footprints allowed)
			)
			(placement
				(enabled no)
				(sheetname "")
			)
			(fill
				(thermal_gap 0.5)
				(thermal_bridge_width 0.5)
				(island_removal_mode 0)
			)
			(polygon
				(pts
					(xy 344.2208 -32.6263) (xy 344.6018 -32.6263) (xy 344.6018 -33.1343) (xy 344.2208 -33.1343)
				)
			)
		)
		(zone
			(layer "F.Cu")
			(hatch none 0.5)
			(connect_pads
				(clearance 0)
			)
			(min_thickness 0.25)
			(keepout
				(tracks allowed)
				(vias not_allowed)
				(pads allowed)
				(copperpour not_allowed)
				(footprints allowed)
			)
			(placement
				(enabled no)
				(sheetname "")
			)
			(fill
				(thermal_gap 0.5)
				(thermal_bridge_width 0.5)
				(island_removal_mode 0)
			)
			(polygon
				(pts
					(xy 344.2208 -32.6263) (xy 344.6018 -32.6263) (xy 344.6018 -33.1343) (xy 344.2208 -33.1343)
				)
			)
		)
	)
	(footprint ""
		(layer "F.Cu")
		(at 409.448 -126.238)
		(property "Reference" "C8B10"
			(at 0 0 0)
			(layer "F.SilkS")
			(hide yes)
			(effects
				(font
					(size 1.27 1.27)
				)
			)
		)
		(property "Value" ""
			(at 0 0 0)
			(layer "F.Fab")
			(effects
				(font
					(size 1.27 1.27)
				)
			)
		)
		(duplicate_pad_numbers_are_jumpers no)
		(fp_poly
			(pts
				(xy -0.4953 -0.2032) (xy 0.4953 -0.2032) (xy 0.4953 1.6002) (xy -0.4953 1.6002)
			)
			(stroke
				(width 0)
				(type default)
			)
			(fill no)
			(layer "F.CrtYd")
		)
		(fp_line
			(start -0.4953 -0.2032)
			(end 0.4953 -0.2032)
			(stroke
				(width 0.1)
				(type default)
			)
			(layer "F.Fab")
		)
		(fp_line
			(start -0.4953 1.6002)
			(end -0.4953 -0.2032)
			(stroke
				(width 0.1)
				(type default)
			)
			(layer "F.Fab")
		)
		(fp_line
			(start 0.4953 -0.2032)
			(end 0.4953 1.6002)
			(stroke
				(width 0.1)
				(type default)
			)
			(layer "F.Fab")
		)
		(fp_line
			(start 0.4953 1.6002)
			(end -0.4953 1.6002)
			(stroke
				(width 0.1)
				(type default)
			)
			(layer "F.Fab")
		)
		(pad "1" smd rect
			(at 0 0)
			(size 0.762 0.889)
			(layers "F.Cu" "F.Mask" "F.Paste")
			(net "P1V05_PCH_STBY")
		)
		(pad "2" smd rect
			(at 0 1.397)
			(size 0.762 0.889)
			(layers "F.Cu" "F.Mask" "F.Paste")
			(net "GND")
		)
		(zone
			(layer "F.Cu")
			(hatch none 0.5)
			(connect_pads
				(clearance 0)
			)
			(min_thickness 0.25)
			(keepout
				(tracks not_allowed)
				(vias allowed)
				(pads allowed)
				(copperpour not_allowed)
				(footprints allowed)
			)
			(placement
				(enabled no)
				(sheetname "")
			)
			(fill
				(thermal_gap 0.5)
				(thermal_bridge_width 0.5)
				(island_removal_mode 0)
			)
			(polygon
				(pts
					(xy 409.067 -125.7935) (xy 409.829 -125.7935) (xy 409.829 -125.2855) (xy 409.067 -125.2855)
				)
			)
		)
	)
	(footprint ""
		(layer "F.Cu")
		(at 337.0326 -128.2065 180)
		(property "Reference" "R7B15"
			(at 0 0 180)
			(layer "F.SilkS")
			(hide yes)
			(effects
				(font
					(size 1.27 1.27)
				)
			)
		)
		(property "Value" ""
			(at 0 0 180)
			(layer "F.Fab")
			(effects
				(font
					(size 1.27 1.27)
				)
			)
		)
		(duplicate_pad_numbers_are_jumpers no)
		(fp_poly
			(pts
				(xy -0.2794 -0.1016) (xy 0.2794 -0.1016) (xy 0.2794 0.9906) (xy -0.2794 0.9906)
			)
			(stroke
				(width 0)
				(type default)
			)
			(fill no)
			(layer "F.CrtYd")
		)
		(fp_line
			(start 0.2794 0.9906)
			(end 0.2794 -0.1016)
			(stroke
				(width 0.1)
				(type default)
			)
			(layer "F.Fab")
		)
		(fp_line
			(start 0.2794 -0.1016)
			(end -0.2794 -0.1016)
			(stroke
				(width 0.1)
				(type default)
			)
			(layer "F.Fab")
		)
		(fp_line
			(start -0.2794 0.9906)
			(end 0.2794 0.9906)
			(stroke
				(width 0.1)
				(type default)
			)
			(layer "F.Fab")
		)
		(fp_line
			(start -0.2794 -0.1016)
			(end -0.2794 0.9906)
			(stroke
				(width 0.1)
				(type default)
			)
			(layer "F.Fab")
		)
		(pad "1" smd rect
			(at 0 0 180)
			(size 0.508 0.508)
			(layers "F.Cu" "F.Mask" "F.Paste")
			(net "VSENSE_PVPP_DEF")
		)
		(pad "2" smd rect
			(at 0 0.889 180)
			(size 0.508 0.508)
			(layers "F.Cu" "F.Mask" "F.Paste")
			(net "VR_FB_PVPP_DEF")
		)
		(zone
			(layer "F.Cu")
			(hatch none 0.5)
			(connect_pads
				(clearance 0)
			)
			(min_thickness 0.25)
			(keepout
				(tracks not_allowed)
				(vias allowed)
				(pads allowed)
				(copperpour not_allowed)
				(footprints allowed)
			)
			(placement
				(enabled no)
				(sheetname "")
			)
			(fill
				(thermal_gap 0.5)
				(thermal_bridge_width 0.5)
				(island_removal_mode 0)
			)
			(polygon
				(pts
					(xy 337.2866 -128.8415) (xy 336.7786 -128.8415) (xy 336.7786 -128.4605) (xy 337.2866 -128.4605)
				)
			)
		)
		(zone
			(layer "F.Cu")
			(hatch none 0.5)
			(connect_pads
				(clearance 0)
			)
			(min_thickness 0.25)
			(keepout
				(tracks allowed)
				(vias not_allowed)
				(pads allowed)
				(copperpour not_allowed)
				(footprints allowed)
			)
			(placement
				(enabled no)
				(sheetname "")
			)
			(fill
				(thermal_gap 0.5)
				(thermal_bridge_width 0.5)
				(island_removal_mode 0)
			)
			(polygon
				(pts
					(xy 337.2866 -128.4605) (xy 336.7786 -128.4605) (xy 336.7786 -128.8415) (xy 337.2866 -128.8415)
				)
			)
		)
	)
	(footprint ""
		(layer "F.Cu")
		(at 171.577 -131.0005 180)
		(property "Reference" "C4B7"
			(at 0 0 180)
			(layer "F.SilkS")
			(hide yes)
			(effects
				(font
					(size 1.27 1.27)
				)
			)
		)
		(property "Value" ""
			(at 0 0 180)
			(layer "F.Fab")
			(effects
				(font
					(size 1.27 1.27)
				)
			)
		)
		(duplicate_pad_numbers_are_jumpers no)
		(fp_poly
			(pts
				(xy 0.3048 -0.1016) (xy 0.3048 0.9906) (xy -0.3048 0.9906) (xy -0.3048 -0.1016)
			)
			(stroke
				(width 0)
				(type default)
			)
			(fill no)
			(layer "F.CrtYd")
		)
		(fp_line
			(start 0.3048 0.9906)
			(end 0.3048 -0.1016)
			(stroke
				(width 0.1)
				(type default)
			)
			(layer "F.Fab")
		)
		(fp_line
			(start 0.3048 -0.1016)
			(end -0.3048 -0.1016)
			(stroke
				(width 0.1)
				(type default)
			)
			(layer "F.Fab")
		)
		(fp_line
			(start -0.3048 0.9906)
			(end 0.3048 0.9906)
			(stroke
				(width 0.1)
				(type default)
			)
			(layer "F.Fab")
		)
		(fp_line
			(start -0.3048 -0.1016)
			(end -0.3048 0.9906)
			(stroke
				(width 0.1)
				(type default)
			)
			(layer "F.Fab")
		)
		(pad "1" smd rect
			(at 0 0 180)
			(size 0.508 0.508)
			(layers "F.Cu" "F.Mask" "F.Paste")
			(net "VR_COMP_PVPP_KLM")
		)
		(pad "2" smd rect
			(at 0 0.889 180)
			(size 0.508 0.508)
			(layers "F.Cu" "F.Mask" "F.Paste")
			(net "VR_FB_PVPP_KLM")
		)
		(zone
			(layer "F.Cu")
			(hatch none 0.5)
			(connect_pads
				(clearance 0)
			)
			(min_thickness 0.25)
			(keepout
				(tracks not_allowed)
				(vias allowed)
				(pads allowed)
				(copperpour not_allowed)
				(footprints allowed)
			)
			(placement
				(enabled no)
				(sheetname "")
			)
			(fill
				(thermal_gap 0.5)
				(thermal_bridge_width 0.5)
				(island_removal_mode 0)
			)
			(polygon
				(pts
					(xy 171.831 -131.6355) (xy 171.323 -131.6355) (xy 171.323 -131.2545) (xy 171.831 -131.2545)
				)
			)
		)
		(zone
			(layer "F.Cu")
			(hatch none 0.5)
			(connect_pads
				(clearance 0)
			)
			(min_thickness 0.25)
			(keepout
				(tracks allowed)
				(vias not_allowed)
				(pads allowed)
				(copperpour not_allowed)
				(footprints allowed)
			)
			(placement
				(enabled no)
				(sheetname "")
			)
			(fill
				(thermal_gap 0.5)
				(thermal_bridge_width 0.5)
				(island_removal_mode 0)
			)
			(polygon
				(pts
					(xy 171.831 -131.2545) (xy 171.323 -131.2545) (xy 171.323 -131.6355) (xy 171.831 -131.6355)
				)
			)
		)
	)
	(footprint ""
		(layer "F.Cu")
		(at 323.6087 -32.42818 -90)
		(property "Reference" "U6F1"
			(at 1.94818 3.61823 90)
			(unlocked yes)
			(layer "F.SilkS")
			(effects
				(font
					(size 0.7874 0.5842)
					(thickness 0.1524)
				)
			)
		)
		(property "Value" ""
			(at 0 0 270)
			(layer "F.Fab")
			(effects
				(font
					(size 1.27 1.27)
				)
			)
		)
		(duplicate_pad_numbers_are_jumpers no)
		(fp_line
			(start 3.225038 2.52476)
			(end 1.348486 2.52476)
			(stroke
				(width 0.1524)
				(type default)
			)
			(layer "F.SilkS")
		)
		(fp_line
			(start 3.225292 -0.57404)
			(end 1.352804 -0.57404)
			(stroke
				(width 0.1524)
				(type default)
			)
			(layer "F.SilkS")
		)
		(fp_circle
			(center -0.946404 -0.683514)
			(end -0.946404 -0.810514)
			(stroke
				(width 0.254)
				(type default)
			)
			(fill no)
			(layer "F.SilkS")
		)
		(fp_poly
			(pts
				(xy 0.7366 -0.57404) (xy 3.8354 -0.57404) (xy 3.8354 2.52476) (xy 0.7366 2.52476)
			)
			(stroke
				(width 0)
				(type default)
			)
			(fill no)
			(layer "F.CrtYd")
		)
		(fp_line
			(start 0.7366 2.52476)
			(end 0.7366 -0.57404)
			(stroke
				(width 0.1)
				(type default)
			)
			(layer "F.Fab")
		)
		(fp_line
			(start 3.8354 2.52476)
			(end 0.7366 2.52476)
			(stroke
				(width 0.1)
				(type default)
			)
			(layer "F.Fab")
		)
		(fp_line
			(start 0.7366 -0.57404)
			(end 3.8354 -0.57404)
			(stroke
				(width 0.1)
				(type default)
			)
			(layer "F.Fab")
		)
		(fp_line
			(start 3.8354 -0.57404)
			(end 3.8354 2.52476)
			(stroke
				(width 0.1)
				(type default)
			)
			(layer "F.Fab")
		)
		(fp_circle
			(center -1.454404 -0.556514)
			(end -1.454404 -0.683514)
			(stroke
				(width 0.254)
				(type default)
			)
			(fill no)
			(layer "F.Fab")
		)
		(pad "1" smd rect
			(at 0 0 270)
			(size 1.778 0.4572)
			(layers "F.Cu" "F.Mask" "F.Paste")
			(net "PVCCIO_CPU0")
		)
		(pad "2" smd rect
			(at 0 0.65024 270)
			(size 1.778 0.4572)
			(layers "F.Cu" "F.Mask" "F.Paste")
			(net "SMB_DDR_ABC_SCL_G")
		)
		(pad "3" smd rect
			(at 0 1.30048 270)
			(size 1.778 0.4572)
			(layers "F.Cu" "F.Mask" "F.Paste")
			(net "SMB_DDR_ABC_SDA_G")
		)
		(pad "4" smd rect
			(at 0 1.95072 270)
			(size 1.778 0.4572)
			(layers "F.Cu" "F.Mask" "F.Paste")
			(net "GND")
		)
		(pad "5" smd rect
			(at 4.572 1.95072 270)
			(size 1.778 0.4572)
			(layers "F.Cu" "F.Mask" "F.Paste")
			(net "TP_SMB_DDR_ABC_EN")
		)
		(pad "6" smd rect
			(at 4.572 1.30048 270)
			(size 1.778 0.4572)
			(layers "F.Cu" "F.Mask" "F.Paste")
			(net "SMB_DDR_ABC_VPP_SDA_R")
		)
		(pad "7" smd rect
			(at 4.572 0.65024 270)
			(size 1.778 0.4572)
			(layers "F.Cu" "F.Mask" "F.Paste")
			(net "SMB_DDR_ABC_VPP_SCL_R")
		)
		(pad "8" smd rect
			(at 4.572 0 270)
			(size 1.778 0.4572)
			(layers "F.Cu" "F.Mask" "F.Paste")
			(net "PVPP_ABC")
		)
	)
)
